# T6G (Grand Teton) — schematic netlist excerpt (pin names and nets, part order shuffled) for the footprints in the layout excerpt that follows; sources: Cadence DE-HDL packaged netlist, KiCad conversion of 04192023_DAF0TMB3IC0_F0TG_MB_C_brd_V02_OCP.brd

J21  SCONN288_DDR506112002KQ  IO  pkg DDR288S_1-1VXC  page 90
  VIN_BULK0  = P12V_MEM_CPU0
  RFU0  = NC
  VIN_MGMT  = P3V3_AUX
  HSCL  = I3C_SPD_DDRE_CPU0_SCL
  HSDA  = I3C_SPD_DDRE_CPU0_SDA
  VSS0  = GND
  DQ0_A  = M_E_CPU0_SA_DQ<0>
  VSS1  = GND
  DQ1_A  = M_E_CPU0_SA_DQ<1>
  VSS2  = GND
  DQS0_A_T  = M_E_CPU0_SA_DQS_DP<0>
  DQS0_A_C  = M_E_CPU0_SA_DQS_DN<0>
  VSS3  = GND
  DQ4_A  = M_E_CPU0_SA_DQ<4>
  VSS4  = GND
  DQ5_A  = M_E_CPU0_SA_DQ<5>
  VSS5  = GND
  DQ8_A  = M_E_CPU0_SA_DQ<8>
  VSS6  = GND
  DQ9_A  = M_E_CPU0_SA_DQ<9>
  VSS7  = GND
  DQS1_A_T  = M_E_CPU0_SA_DQS_DP<1>
  DQS1_A_C  = M_E_CPU0_SA_DQS_DN<1>
  VSS8  = GND
  DQ12_A  = M_E_CPU0_SA_DQ<12>
  VSS9  = GND
  DQ13_A  = M_E_CPU0_SA_DQ<13>
  VSS10  = GND
  DQ16_A  = M_E_CPU0_SA_DQ<16>
  VSS11  = GND
  DQ17_A  = M_E_CPU0_SA_DQ<17>
  VSS12  = GND
  DQS2_A_T  = M_E_CPU0_SA_DQS_DP<2>
  DQS2_A_C  = M_E_CPU0_SA_DQS_DN<2>
  VSS13  = GND
  DQ20_A  = M_E_CPU0_SA_DQ<20>
  VSS14  = GND
  DQ21_A  = M_E_CPU0_SA_DQ<21>
  VSS15  = GND
  DQ24_A  = M_E_CPU0_SA_DQ<24>
  VSS16  = GND
  DQ25_A  = M_E_CPU0_SA_DQ<25>
  VSS17  = GND
  DQS3_A_T  = M_E_CPU0_SA_DQS_DP<3>
  DQS3_A_C  = M_E_CPU0_SA_DQS_DN<3>
  VSS18  = GND
  DQ28_A  = M_E_CPU0_SA_DQ<28>
  VSS19  = GND
  DQ29_A  = M_E_CPU0_SA_DQ<29>
  VSS20  = GND
  CB0_A  = M_E_CPU0_SA_CB<0>
  VSS21  = GND
  CB1_A  = M_E_CPU0_SA_CB<1>
  VSS22  = GND
  DQS4_A_T  = M_E_CPU0_SA_DQS_DP<4>
  DQS4_A_C  = M_E_CPU0_SA_DQS_DN<4>
  VSS23  = GND
  CB4_A  = M_E_CPU0_SA_CB<4>
  VSS24  = GND
  CB5_A  = M_E_CPU0_SA_CB<5>
  VSS25  = GND
  ALERT_N  = M_E_CPU0_ALERT_N
  VSS26  = GND
  CS0_A_N  = M_E_CPU0_SA_CS_N<0>
  VSS27  = GND
  CA0_A  = M_E_CPU0_SA_CA<0>
  VSS28  = GND
  CA2_A  = M_E_CPU0_SA_CA<2>
  VSS29  = GND
  CA4_A  = M_E_CPU0_SA_CA<4>
  VSS30  = GND
  CA6_A  = M_E_CPU0_SA_CA<6>
  VSS31  = GND
  PAR_A  = M_E_CPU0_SA_PAR
  VSS32  = GND
  CA0_B  = M_E_CPU0_SB_CA<0>
  VSS33  = GND
  CA2_B  = M_E_CPU0_SB_CA<2>
  VSS34  = GND
  CA4_B  = M_E_CPU0_SB_CA<4>
  VSS35  = GND
  CA6_B  = M_E_CPU0_SB_CA<6>
  VSS36  = GND
  CS0_B_N  = M_E_CPU0_SB_CS_N<0>
  VSS37  = GND
  \lbd||rsp_a_n\  = M_E_CPU0_SA_RSP<0>
  \lbs||rsp_b_n\  = M_E_CPU0_SB_RSP<0>
  VSS38  = GND
  CB4_B  = M_E_CPU0_SB_CB<4>
  VSS39  = GND
  CB5_B  = M_E_CPU0_SB_CB<5>
  VSS40  = GND
  \dqs9_b_t||tdqs9_b_t||dbi4_b_n\  = M_E_CPU0_SB_DQS_DP<9>
  \dqs9_b_c||tdqs9_b_c\  = M_E_CPU0_SB_DQS_DN<9>
  VSS41  = GND
  CB0_B  = M_E_CPU0_SB_CB<0>
  VSS42  = GND
  CB1_B  = M_E_CPU0_SB_CB<1>
  VSS43  = GND
  DQ0_B  = M_E_CPU0_SB_DQ<0>
  VSS44  = GND
  DQ1_B  = M_E_CPU0_SB_DQ<1>
  VSS45  = GND
  DQS0_B_T  = M_E_CPU0_SB_DQS_DP<0>
  DQS0_B_C  = M_E_CPU0_SB_DQS_DN<0>
  VSS46  = GND
  DQ4_B  = M_E_CPU0_SB_DQ<4>
  VSS47  = GND
  DQ5_B  = M_E_CPU0_SB_DQ<5>
  VSS48  = GND
  DQ8_B  = M_E_CPU0_SB_DQ<8>
  VSS49  = GND
  DQ9_B  = M_E_CPU0_SB_DQ<9>
  VSS50  = GND
  DQS1_B_T  = M_E_CPU0_SB_DQS_DP<1>
  DQS1_B_C  = M_E_CPU0_SB_DQS_DN<1>
  VSS51  = GND
  DQ12_B  = M_E_CPU0_SB_DQ<12>
  VSS52  = GND
  DQ13_B  = M_E_CPU0_SB_DQ<13>
  VSS53  = GND
  DQ16_B  = M_E_CPU0_SB_DQ<16>
  VSS54  = GND
  DQ17_B  = M_E_CPU0_SB_DQ<17>
  VSS55  = GND
  DQS2_B_T  = M_E_CPU0_SB_DQS_DP<2>
  DQS2_B_C  = M_E_CPU0_SB_DQS_DN<2>
  VSS56  = GND
  DQ20_B  = M_E_CPU0_SB_DQ<20>
  VSS57  = GND
  DQ21_B  = M_E_CPU0_SB_DQ<21>
  VSS58  = GND
  DQ24_B  = M_E_CPU0_SB_DQ<24>
  VSS59  = GND
  DQ25_B  = M_E_CPU0_SB_DQ<25>
  VSS60  = GND
  DQS3_B_T  = M_E_CPU0_SB_DQS_DP<3>
  DQS3_B_C  = M_E_CPU0_SB_DQS_DN<3>
  VSS61  = GND
  DQ28_B  = M_E_CPU0_SB_DQ<28>
  VSS62  = GND
  DQ29_B  = M_E_CPU0_SB_DQ<29>
  VSS63  = GND
  RFU1  = NC
  VIN_BULK1  = P12V_MEM_CPU0
  VIN_BULK2  = P12V_MEM_CPU0
  \pwr_good||fail_n\  = PWRGD_CHE_CPU0_DIMM
  HAS  = PD_CHE_CPU0_DIMM_SAA
  RFU2  = NC
  RFU3  = NC
  VSS64  = GND
  DQ2_A  = M_E_CPU0_SA_DQ<2>
  VSS65  = GND
  DQ3_A  = M_E_CPU0_SA_DQ<3>
  VSS66  = GND
  \dqs5_a_c||tdqs5_a_c||dqs5_a_t||tdqs5_a_t\  = M_E_CPU0_SA_DQS_DN<5>
  \dqs5_a_t||tdqs5_a_t\  = M_E_CPU0_SA_DQS_DP<5>
  VSS67  = GND
  DQ6_A  = M_E_CPU0_SA_DQ<6>
  VSS68  = GND
  DQ7_A  = M_E_CPU0_SA_DQ<7>
  VSS69  = GND
  DQ10_A  = M_E_CPU0_SA_DQ<10>
  VSS70  = GND
  DQ11_A  = M_E_CPU0_SA_DQ<11>
  VSS71  = GND
  \dqs6_a_c||tdqs6_a_c||dqs6_a_t||tdqs6_a_t\  = M_E_CPU0_SA_DQS_DN<6>
  \dqs6_a_t||tdqs6_a_t\  = M_E_CPU0_SA_DQS_DP<6>
  VSS72  = GND
  DQ14_A  = M_E_CPU0_SA_DQ<14>
  VSS73  = GND
  DQ15_A  = M_E_CPU0_SA_DQ<15>
  VSS74  = GND
  DQ18_A  = M_E_CPU0_SA_DQ<18>
  VSS75  = GND
  DQ19_A  = M_E_CPU0_SA_DQ<19>
  VSS76  = GND
  \dqs7_a_c||tdqs7_a_c\  = M_E_CPU0_SA_DQS_DN<7>
  \dqs7_a_t||tdqs7_a_t\  = M_E_CPU0_SA_DQS_DP<7>
  VSS77  = GND
  DQ22_A  = M_E_CPU0_SA_DQ<22>
  VSS78  = GND
  DQ23_A  = M_E_CPU0_SA_DQ<23>
  VSS79  = GND
  DQ26_A  = M_E_CPU0_SA_DQ<26>
  VSS80  = GND
  DQ27_A  = M_E_CPU0_SA_DQ<27>
  VSS81  = GND
  \dqs8_a_c||tdqs8_a_c\  = M_E_CPU0_SA_DQS_DN<8>
  \dqs8_a_t||tdqs8_a_t\  = M_E_CPU0_SA_DQS_DP<8>
  VSS82  = GND
  DQ30_A  = M_E_CPU0_SA_DQ<30>
  VSS83  = GND
  DQ31_A  = M_E_CPU0_SA_DQ<31>
  VSS84  = GND
  CB2_A  = M_E_CPU0_SA_CB<2>
  VSS85  = GND
  CB3_A  = M_E_CPU0_SA_CB<3>
  VSS86  = GND
  \dqs9_a_c||tdqs9_a_c\  = M_E_CPU0_SA_DQS_DN<9>
  \dqs9_a_t||tdqs9_a_t\  = M_E_CPU0_SA_DQS_DP<9>
  VSS87  = GND
  CB6_A  = M_E_CPU0_SA_CB<6>
  VSS88  = GND
  CB7_A  = M_E_CPU0_SA_CB<7>
  VSS89  = GND
  RESET_N  = M_E_CPU0_RESET_N
  VSS90  = GND
  CS1_A_N  = M_E_CPU0_SA_CS_N<1>
  VSS91  = GND
  CA1_A  = M_E_CPU0_SA_CA<1>
  VSS92  = GND
  CA3_A  = M_E_CPU0_SA_CA<3>
  VSS93  = GND
  CA5_A  = M_E_CPU0_SA_CA<5>
  VSS94  = GND
  CK_T  = M_E_CPU0_CLK_DP<0>
  CK_C  = M_E_CPU0_CLK_DN<0>
  VSS95  = GND
  RFU4  = NC
  CA1_B  = M_E_CPU0_SB_CA<1>
  VSS96  = GND
  CA3_B  = M_E_CPU0_SB_CA<3>
  VSS97  = GND
  CA5_B  = M_E_CPU0_SB_CA<5>
  VSS98  = GND
  PAR_B  = M_E_CPU0_SB_PAR
  VSS99  = GND
  CS1_B_N  = M_E_CPU0_SB_CS_N<1>
  VSS100  = GND
  RFU5  = NC
  RFU6  = NC
  VSS101  = GND
  CB6_B  = M_E_CPU0_SB_CB<6>
  VSS102  = GND
  CB7_B  = M_E_CPU0_SB_CB<7>
  VSS103  = GND
  DQS4_B_C  = M_E_CPU0_SB_DQS_DN<4>
  DQS4_B_T  = M_E_CPU0_SB_DQS_DP<4>
  VSS104  = GND
  CB2_B  = M_E_CPU0_SB_CB<2>
  VSS105  = GND
  CB3_B  = M_E_CPU0_SB_CB<3>
  VSS106  = GND
  DQ2_B  = M_E_CPU0_SB_DQ<2>
  VSS107  = GND
  DQ3_B  = M_E_CPU0_SB_DQ<3>
  VSS108  = GND
  \dqs5_b_c||tdqs5_b_c\  = M_E_CPU0_SB_DQS_DN<5>
  \dqs5_b_t||tdqs5_b_t\  = M_E_CPU0_SB_DQS_DP<5>
  VSS109  = GND
  DQ6_B  = M_E_CPU0_SB_DQ<6>
  VSS110  = GND
  DQ7_B  = M_E_CPU0_SB_DQ<7>
  VSS111  = GND
  DQ10_B  = M_E_CPU0_SB_DQ<10>
  VSS112  = GND
  DQ11_B  = M_E_CPU0_SB_DQ<11>
  VSS113  = GND
  \dqs6_b_c||tdqs6_b_c\  = M_E_CPU0_SB_DQS_DN<6>
  \dqs6_b_t||tdqs6_b_t\  = M_E_CPU0_SB_DQS_DP<6>
  VSS114  = GND
  DQ14_B  = M_E_CPU0_SB_DQ<14>
  VSS115  = GND
  DQ15_B  = M_E_CPU0_SB_DQ<15>
  VSS116  = GND
  DQ18_B  = M_E_CPU0_SB_DQ<18>
  VSS117  = GND
  DQ19_B  = M_E_CPU0_SB_DQ<19>
  VSS118  = GND
  \dqs7_b_c||tdqs7_b_c\  = M_E_CPU0_SB_DQS_DN<7>
  \dqs7_b_t||tdqs7_b_t\  = M_E_CPU0_SB_DQS_DP<7>
  VSS119  = GND
  DQ22_B  = M_E_CPU0_SB_DQ<22>
  VSS120  = GND
  DQ23_B  = M_E_CPU0_SB_DQ<23>
  VSS121  = GND
  DQ26_B  = M_E_CPU0_SB_DQ<26>
  VSS122  = GND
  DQ27_B  = M_E_CPU0_SB_DQ<27>
  VSS123  = GND
  \dqs8_b_c||tdqs8_b_c\  = M_E_CPU0_SB_DQS_DN<8>
  \dqs8_b_t||tdqs8_b_t\  = M_E_CPU0_SB_DQS_DP<8>
  VSS124  = GND
  DQ30_B  = M_E_CPU0_SB_DQ<30>
  VSS125  = GND
  DQ31_B  = M_E_CPU0_SB_DQ<31>
  VSS126  = GND
  G1  = GND
  G2  = GND
  G3  = GND

(kicad_pcb
	(version 20260206)
	(generator "pcbnew")
	(generator_version "10.0")
	(general
		(thickness 1.6)
		(legacy_teardrops no)
	)
	(paper "A4")
	(title_block
		(title "04192023_DAF0TMB3IC0_F0TG_MB_C_brd_V02_OCP.brd")
		(comment 1 "Grand Teton / footprint 3 of 8354 (J21), pads 93-138 of 291")
	)
	(layers
		(0 "F.Cu" signal "TOP")
		(4 "In1.Cu" signal "GND")
		(6 "In2.Cu" signal "IN1")
		(8 "In3.Cu" signal "GND1")
		(10 "In4.Cu" signal "IN2")
		(12 "In5.Cu" signal "GND2")
		(14 "In6.Cu" signal "IN3")
		(16 "In7.Cu" signal "GND3")
		(18 "In8.Cu" signal "VCC")
		(20 "In9.Cu" signal "VCC1")
		(22 "In10.Cu" signal "GND4")
		(24 "In11.Cu" signal "IN4")
		(26 "In12.Cu" signal "GND5")
		(28 "In13.Cu" signal "IN5")
		(30 "In14.Cu" signal "GND6")
		(32 "In15.Cu" signal "IN6")
		(34 "In16.Cu" signal "GND7")
		(2 "B.Cu" signal "BOTTOM")
		(9 "F.Adhes" user "F.Adhesive")
		(11 "B.Adhes" user "B.Adhesive")
		(13 "F.Paste" user "Package Geometry/Pastemask Top")
		(15 "B.Paste" user "Package Geometry/Pastemask Bottom")
		(5 "F.SilkS" user "Ref Des/Silkscreen Top")
		(7 "B.SilkS" user "Ref Des/Silkscreen Bottom")
		(1 "F.Mask" user "Board Geometry/Soldermask Top")
		(3 "B.Mask" user "Board Geometry/Soldermask Bottom")
		(17 "Dwgs.User" user "User.Drawings")
		(19 "Cmts.User" user "User.Comments")
		(21 "Eco1.User" user "User.Eco1")
		(23 "Eco2.User" user "User.Eco2")
		(25 "Edge.Cuts" user "Board Geometry/Outline")
		(27 "Margin" user)
		(31 "F.CrtYd" user "Package Geometry/Place Bound Top")
		(29 "B.CrtYd" user "Package Geometry/Place Bound Bottom")
		(35 "F.Fab" user "Ref Des/Assembly Top")
		(33 "B.Fab" user "Ref Des/Assembly Bottom")
	)
	(footprint ""
		(layer "F.Cu")
		(at 275.142198 -255.560068 180)
		(property "Reference" "J21"
			(at -2.2098 -81.984088 0)
			(unlocked yes)
			(layer "F.SilkS")
			(effects
				(font
					(size 0.7874 0.5842)
					(thickness 0.1524)
				)
			)
		)
		(property "Value" ""
			(at 0 0 180)
			(layer "F.Fab")
			(effects
				(font
					(size 1.27 1.27)
				)
			)
		)
		(duplicate_pad_numbers_are_jumpers no)
		(pad "93" smd rect
			(at -2.050034 19.975068 90)
			(size 0.519938 1.4986)
			(layers "F.Cu" "F.Mask" "F.Paste")
			(net "M_E_CPU0_SB_DQS_DP<9>")
		)
		(pad "94" smd rect
			(at -2.050034 20.824952 90)
			(size 0.519938 1.4986)
			(layers "F.Cu" "F.Mask" "F.Paste")
			(net "M_E_CPU0_SB_DQS_DN<9>")
		)
		(pad "95" smd rect
			(at -2.050034 21.67509 90)
			(size 0.519938 1.4986)
			(layers "F.Cu" "F.Mask" "F.Paste")
			(net "GND")
		)
		(pad "96" smd rect
			(at -2.050034 22.524974 90)
			(size 0.519938 1.4986)
			(layers "F.Cu" "F.Mask" "F.Paste")
			(net "M_E_CPU0_SB_CB<0>")
		)
		(pad "97" smd rect
			(at -2.050034 23.375112 90)
			(size 0.519938 1.4986)
			(layers "F.Cu" "F.Mask" "F.Paste")
			(net "GND")
		)
		(pad "98" smd rect
			(at -2.050034 24.224996 90)
			(size 0.519938 1.4986)
			(layers "F.Cu" "F.Mask" "F.Paste")
			(net "M_E_CPU0_SB_CB<1>")
		)
		(pad "99" smd rect
			(at -2.050034 25.07488 90)
			(size 0.519938 1.4986)
			(layers "F.Cu" "F.Mask" "F.Paste")
			(net "GND")
		)
		(pad "100" smd rect
			(at -2.050034 25.925018 90)
			(size 0.519938 1.4986)
			(layers "F.Cu" "F.Mask" "F.Paste")
			(net "M_E_CPU0_SB_DQ<0>")
		)
		(pad "101" smd rect
			(at -2.050034 26.774902 90)
			(size 0.519938 1.4986)
			(layers "F.Cu" "F.Mask" "F.Paste")
			(net "GND")
		)
		(pad "102" smd rect
			(at -2.050034 27.62504 90)
			(size 0.519938 1.4986)
			(layers "F.Cu" "F.Mask" "F.Paste")
			(net "M_E_CPU0_SB_DQ<1>")
		)
		(pad "103" smd rect
			(at -2.050034 28.474924 90)
			(size 0.519938 1.4986)
			(layers "F.Cu" "F.Mask" "F.Paste")
			(net "GND")
		)
		(pad "104" smd rect
			(at -2.050034 29.325062 90)
			(size 0.519938 1.4986)
			(layers "F.Cu" "F.Mask" "F.Paste")
			(net "M_E_CPU0_SB_DQS_DP<0>")
		)
		(pad "105" smd rect
			(at -2.050034 30.174946 90)
			(size 0.519938 1.4986)
			(layers "F.Cu" "F.Mask" "F.Paste")
			(net "M_E_CPU0_SB_DQS_DN<0>")
		)
		(pad "106" smd rect
			(at -2.050034 31.025084 90)
			(size 0.519938 1.4986)
			(layers "F.Cu" "F.Mask" "F.Paste")
			(net "GND")
		)
		(pad "107" smd rect
			(at -2.050034 31.874968 90)
			(size 0.519938 1.4986)
			(layers "F.Cu" "F.Mask" "F.Paste")
			(net "M_E_CPU0_SB_DQ<4>")
		)
		(pad "108" smd rect
			(at -2.050034 32.725106 90)
			(size 0.519938 1.4986)
			(layers "F.Cu" "F.Mask" "F.Paste")
			(net "GND")
		)
		(pad "109" smd rect
			(at -2.050034 33.57499 90)
			(size 0.519938 1.4986)
			(layers "F.Cu" "F.Mask" "F.Paste")
			(net "M_E_CPU0_SB_DQ<5>")
		)
		(pad "110" smd rect
			(at -2.050034 34.425128 90)
			(size 0.519938 1.4986)
			(layers "F.Cu" "F.Mask" "F.Paste")
			(net "GND")
		)
		(pad "111" smd rect
			(at -2.050034 35.275012 90)
			(size 0.519938 1.4986)
			(layers "F.Cu" "F.Mask" "F.Paste")
			(net "M_E_CPU0_SB_DQ<8>")
		)
		(pad "112" smd rect
			(at -2.050034 36.124896 90)
			(size 0.519938 1.4986)
			(layers "F.Cu" "F.Mask" "F.Paste")
			(net "GND")
		)
		(pad "113" smd rect
			(at -2.050034 36.975034 90)
			(size 0.519938 1.4986)
			(layers "F.Cu" "F.Mask" "F.Paste")
			(net "M_E_CPU0_SB_DQ<9>")
		)
		(pad "114" smd rect
			(at -2.050034 37.824918 90)
			(size 0.519938 1.4986)
			(layers "F.Cu" "F.Mask" "F.Paste")
			(net "GND")
		)
		(pad "115" smd rect
			(at -2.050034 38.675056 90)
			(size 0.519938 1.4986)
			(layers "F.Cu" "F.Mask" "F.Paste")
			(net "M_E_CPU0_SB_DQS_DP<1>")
		)
		(pad "116" smd rect
			(at -2.050034 39.52494 90)
			(size 0.519938 1.4986)
			(layers "F.Cu" "F.Mask" "F.Paste")
			(net "M_E_CPU0_SB_DQS_DN<1>")
		)
		(pad "117" smd rect
			(at -2.050034 40.375078 90)
			(size 0.519938 1.4986)
			(layers "F.Cu" "F.Mask" "F.Paste")
			(net "GND")
		)
		(pad "118" smd rect
			(at -2.050034 41.224962 90)
			(size 0.519938 1.4986)
			(layers "F.Cu" "F.Mask" "F.Paste")
			(net "M_E_CPU0_SB_DQ<12>")
		)
		(pad "119" smd rect
			(at -2.050034 42.0751 90)
			(size 0.519938 1.4986)
			(layers "F.Cu" "F.Mask" "F.Paste")
			(net "GND")
		)
		(pad "120" smd rect
			(at -2.050034 42.924984 90)
			(size 0.519938 1.4986)
			(layers "F.Cu" "F.Mask" "F.Paste")
			(net "M_E_CPU0_SB_DQ<13>")
		)
		(pad "121" smd rect
			(at -2.050034 43.775122 90)
			(size 0.519938 1.4986)
			(layers "F.Cu" "F.Mask" "F.Paste")
			(net "GND")
		)
		(pad "122" smd rect
			(at -2.050034 44.625006 90)
			(size 0.519938 1.4986)
			(layers "F.Cu" "F.Mask" "F.Paste")
			(net "M_E_CPU0_SB_DQ<16>")
		)
		(pad "123" smd rect
			(at -2.050034 45.47489 90)
			(size 0.519938 1.4986)
			(layers "F.Cu" "F.Mask" "F.Paste")
			(net "GND")
		)
		(pad "124" smd rect
			(at -2.050034 46.325028 90)
			(size 0.519938 1.4986)
			(layers "F.Cu" "F.Mask" "F.Paste")
			(net "M_E_CPU0_SB_DQ<17>")
		)
		(pad "125" smd rect
			(at -2.050034 47.174912 90)
			(size 0.519938 1.4986)
			(layers "F.Cu" "F.Mask" "F.Paste")
			(net "GND")
		)
		(pad "126" smd rect
			(at -2.050034 48.02505 90)
			(size 0.519938 1.4986)
			(layers "F.Cu" "F.Mask" "F.Paste")
			(net "M_E_CPU0_SB_DQS_DP<2>")
		)
		(pad "127" smd rect
			(at -2.050034 48.874934 90)
			(size 0.519938 1.4986)
			(layers "F.Cu" "F.Mask" "F.Paste")
			(net "M_E_CPU0_SB_DQS_DN<2>")
		)
		(pad "128" smd rect
			(at -2.050034 49.725072 90)
			(size 0.519938 1.4986)
			(layers "F.Cu" "F.Mask" "F.Paste")
			(net "GND")
		)
		(pad "129" smd rect
			(at -2.050034 50.574956 90)
			(size 0.519938 1.4986)
			(layers "F.Cu" "F.Mask" "F.Paste")
			(net "M_E_CPU0_SB_DQ<20>")
		)
		(pad "130" smd rect
			(at -2.050034 51.425094 90)
			(size 0.519938 1.4986)
			(layers "F.Cu" "F.Mask" "F.Paste")
			(net "GND")
		)
		(pad "131" smd rect
			(at -2.050034 52.274978 90)
			(size 0.519938 1.4986)
			(layers "F.Cu" "F.Mask" "F.Paste")
			(net "M_E_CPU0_SB_DQ<21>")
		)
		(pad "132" smd rect
			(at -2.050034 53.125116 90)
			(size 0.519938 1.4986)
			(layers "F.Cu" "F.Mask" "F.Paste")
			(net "GND")
		)
		(pad "133" smd rect
			(at -2.050034 53.975 90)
			(size 0.519938 1.4986)
			(layers "F.Cu" "F.Mask" "F.Paste")
			(net "M_E_CPU0_SB_DQ<24>")
		)
		(pad "134" smd rect
			(at -2.050034 54.824884 90)
			(size 0.519938 1.4986)
			(layers "F.Cu" "F.Mask" "F.Paste")
			(net "GND")
		)
		(pad "135" smd rect
			(at -2.050034 55.675022 90)
			(size 0.519938 1.4986)
			(layers "F.Cu" "F.Mask" "F.Paste")
			(net "M_E_CPU0_SB_DQ<25>")
		)
		(pad "136" smd rect
			(at -2.050034 56.524906 90)
			(size 0.519938 1.4986)
			(layers "F.Cu" "F.Mask" "F.Paste")
			(net "GND")
		)
		(pad "137" smd rect
			(at -2.050034 57.375044 90)
			(size 0.519938 1.4986)
			(layers "F.Cu" "F.Mask" "F.Paste")
			(net "M_E_CPU0_SB_DQS_DP<3>")
		)
		(pad "138" smd rect
			(at -2.050034 58.224928 90)
			(size 0.519938 1.4986)
			(layers "F.Cu" "F.Mask" "F.Paste")
			(net "M_E_CPU0_SB_DQS_DN<3>")
		)
	)
)
